FILE_TYPE = CONNECTIVITY;
{Allegro Design Entry HDL 16.6-p007 (v16-6-112F) 10/10/2012}
"PAGE_NUMBER" = 62;
0"NC";
1"M_M_DQS_DP<17:0>";
2"M_M_DQS_DN<17:0>";
3"M_M_MA<17:0>";
4"M_M_BA<1:0>";
5"M_M_BG<1:0>";
6"M_M_CKE<3:0>";
7"M_M_CS_N<7:0>";
8"M_M_ODT<3:0>";
9"M_M_DQ<63:0>";
10"M_M_CLK_DN<3:0>";
11"M_M_CLK_DP<3:0>";
12"M_M_ECC<7:0>";
13"M_M_C<2>";
14"M_M_ECC<0>";
15"M_M_ECC<1>";
16"M_M_ECC<2>";
17"M_M_ECC<3>";
18"M_M_ECC<4>";
19"M_M_ECC<5>";
20"M_M_ECC<6>";
21"M_M_ECC<7>";
22"M_M_DQ<0>";
23"M_M_DQ<1>";
24"M_M_DQ<2>";
25"M_M_DQ<3>";
26"M_M_DQ<4>";
27"M_M_DQ<5>";
28"M_M_DQ<6>";
29"M_M_DQ<7>";
30"M_M_DQ<8>";
31"M_M_DQ<9>";
32"M_M_DQ<10>";
33"M_M_CLK_DP<0>";
34"M_M_CLK_DP<1>";
35"M_M_CLK_DP<2>";
36"M_M_CLK_DP<3>";
37"M_M_CLK_DN<0>";
38"M_M_CLK_DN<1>";
39"M_M_CLK_DN<2>";
40"M_M_CLK_DN<3>";
41"M_M_DQ<11>";
42"M_M_DQ<12>";
43"M_M_DQ<13>";
44"M_M_DQ<14>";
45"M_M_DQ<15>";
46"M_M_DQ<16>";
47"M_M_DQ<17>";
48"M_M_DQ<18>";
49"M_M_DQ<19>";
50"M_M_DQ<20>";
51"M_M_DQ<21>";
52"M_M_DQ<22>";
53"M_M_DQ<23>";
54"M_M_DQ<24>";
55"M_M_DQ<25>";
56"M_M_DQ<26>";
57"M_M_DQ<27>";
58"M_M_DQ<28>";
59"M_M_DQ<29>";
60"M_M_DQ<30>";
61"M_M_DQ<31>";
62"M_M_DQ<32>";
63"M_M_DQ<33>";
64"M_M_DQ<34>";
65"M_M_DQ<35>";
66"M_M_DQ<36>";
67"M_M_DQ<37>";
68"M_M_DQ<38>";
69"M_M_DQ<39>";
70"M_M_DQ<40>";
71"M_M_DQ<41>";
72"M_M_DQ<42>";
73"M_M_DQ<43>";
74"M_M_DQ<44>";
75"M_M_DQ<45>";
76"M_M_DQ<46>";
77"M_M_DQ<47>";
78"M_M_DQ<48>";
79"M_M_DQ<49>";
80"M_M_DQ<50>";
81"M_M_DQ<51>";
82"M_M_DQ<52>";
83"M_M_DQ<53>";
84"M_M_DQ<54>";
85"M_M_DQ<55>";
86"M_M_DQ<56>";
87"M_M_DQ<57>";
88"M_M_DQ<58>";
89"M_M_DQ<59>";
90"M_M_DQ<60>";
91"M_M_DQ<61>";
92"M_M_DQ<62>";
93"M_M_DQ<63>";
94"M_M_ODT<0>";
95"M_M_ODT<1>";
96"M_M_ODT<2>";
97"M_M_ODT<3>";
98"M_M_MA<0>";
99"M_M_MA<1>";
100"M_M_MA<2>";
101"M_M_CS_N<0>";
102"M_M_CS_N<1>";
103"M_M_CS_N<2>";
104"M_M_CS_N<3>";
105"M_M_CS_N<4>";
106"M_M_CS_N<5>";
107"M_M_CS_N<6>";
108"M_M_CS_N<7>";
109"M_M_CKE<0>";
110"M_M_CKE<1>";
111"M_M_CKE<2>";
112"M_M_CKE<3>";
113"M_M_BG<0>";
114"M_M_BG<1>";
115"M_M_BA<0>";
116"M_M_BA<1>";
117"M_M_PAR";
118"M_M_ACT_N";
119"M_M_ALERT_N";
120"M_M_MA<3>";
121"M_M_MA<4>";
122"M_M_MA<5>";
123"M_M_MA<6>";
124"M_M_MA<7>";
125"M_M_MA<8>";
126"M_M_MA<9>";
127"M_M_MA<10>";
128"M_M_MA<11>";
129"M_M_MA<12>";
130"M_M_MA<13>";
131"M_M_MA<14>";
132"M_M_MA<15>";
133"M_M_MA<16>";
134"M_M_MA<17>";
135"M_M_DQS_DP<0>";
136"M_M_DQS_DP<1>";
137"M_M_DQS_DP<2>";
138"M_M_DQS_DP<3>";
139"M_M_DQS_DP<4>";
140"M_M_DQS_DP<5>";
141"M_M_DQS_DN<0>";
142"M_M_DQS_DN<1>";
143"M_M_DQS_DN<2>";
144"M_M_DQS_DN<3>";
145"M_M_DQS_DN<4>";
146"M_M_DQS_DN<5>";
147"M_M_DQS_DN<6>";
148"M_M_DQS_DN<7>";
149"M_M_DQS_DN<8>";
150"M_M_DQS_DN<9>";
151"M_M_DQS_DN<10>";
152"M_M_DQS_DN<11>";
153"M_M_DQS_DN<12>";
154"M_M_DQS_DN<13>";
155"M_M_DQS_DN<14>";
156"M_M_DQS_DN<15>";
157"M_M_DQS_DN<16>";
158"M_M_DQS_DN<17>";
159"M_M_DQS_DP<6>";
160"M_M_DQS_DP<7>";
161"M_M_DQS_DP<8>";
162"M_M_DQS_DP<9>";
163"M_M_DQS_DP<10>";
164"M_M_DQS_DP<11>";
165"M_M_DQS_DP<12>";
166"M_M_DQS_DP<13>";
167"M_M_DQS_DP<14>";
168"M_M_DQS_DP<15>";
169"M_M_DQS_DP<16>";
170"M_M_DQS_DP<17>";
%"TAP"
"6","(-5600,800)","0","mstr_standard","I10";
;
HDL_TAP"TRUE"
BODY_TYPE"PLUMBING"
CDS_LIB"mstr_standard";
"B \NAC \NWC"11;
"S \NAC"
BN"0"33;
%"TAP"
"6","(-2875,1550)","2","mstr_standard","I100";
;
HDL_TAP"TRUE"
BODY_TYPE"PLUMBING"
CDS_LIB"mstr_standard";
"B \NAC \NWC"8;
"S \NAC"
BN"3"97;
%"TAP"
"6","(-2875,1500)","2","mstr_standard","I101";
;
HDL_TAP"TRUE"
BODY_TYPE"PLUMBING"
CDS_LIB"mstr_standard";
"B \NAC \NWC"8;
"S \NAC"
BN"2"96;
%"TAP"
"6","(-2875,1450)","2","mstr_standard","I102";
;
HDL_TAP"TRUE"
BODY_TYPE"PLUMBING"
CDS_LIB"mstr_standard";
"B \NAC \NWC"8;
"S \NAC"
BN"1"95;
%"TAP"
"6","(-2875,1650)","2","mstr_standard","I103";
;
HDL_TAP"TRUE"
BODY_TYPE"PLUMBING"
CDS_LIB"mstr_standard";
"B \NAC \NWC"6;
"S \NAC"
BN"0"109;
%"TAP"
"6","(-2875,1700)","2","mstr_standard","I104";
;
HDL_TAP"TRUE"
BODY_TYPE"PLUMBING"
CDS_LIB"mstr_standard";
"B \NAC \NWC"6;
"S \NAC"
BN"1"110;
%"TAP"
"6","(-2875,1750)","2","mstr_standard","I105";
;
HDL_TAP"TRUE"
BODY_TYPE"PLUMBING"
CDS_LIB"mstr_standard";
"B \NAC \NWC"6;
"S \NAC"
BN"2"111;
%"TAP"
"6","(-2875,1800)","2","mstr_standard","I106";
;
HDL_TAP"TRUE"
BODY_TYPE"PLUMBING"
CDS_LIB"mstr_standard";
"B \NAC \NWC"6;
"S \NAC"
BN"3"112;
%"TAP"
"6","(-2875,1900)","2","mstr_standard","I107";
;
HDL_TAP"TRUE"
BODY_TYPE"PLUMBING"
CDS_LIB"mstr_standard";
"B \NAC \NWC"3;
"S \NAC"
BN"0"98;
%"TAP"
"6","(-2875,1950)","2","mstr_standard","I108";
;
HDL_TAP"TRUE"
BODY_TYPE"PLUMBING"
CDS_LIB"mstr_standard";
"B \NAC \NWC"3;
"S \NAC"
BN"1"99;
%"TAP"
"6","(-2875,2050)","2","mstr_standard","I109";
;
HDL_TAP"TRUE"
BODY_TYPE"PLUMBING"
CDS_LIB"mstr_standard";
"B \NAC \NWC"3;
"S \NAC"
BN"3"120;
%"TAP"
"6","(-5600,900)","0","mstr_standard","I11";
;
HDL_TAP"TRUE"
BODY_TYPE"PLUMBING"
CDS_LIB"mstr_standard";
"B \NAC \NWC"11;
"S \NAC"
BN"2"35;
%"TAP"
"6","(-2875,2000)","2","mstr_standard","I110";
;
HDL_TAP"TRUE"
BODY_TYPE"PLUMBING"
CDS_LIB"mstr_standard";
"B \NAC \NWC"3;
"S \NAC"
BN"2"100;
%"TAP"
"6","(-2875,2100)","2","mstr_standard","I111";
;
HDL_TAP"TRUE"
BODY_TYPE"PLUMBING"
CDS_LIB"mstr_standard";
"B \NAC \NWC"3;
"S \NAC"
BN"4"121;
%"TAP"
"6","(-2875,2150)","2","mstr_standard","I112";
;
HDL_TAP"TRUE"
BODY_TYPE"PLUMBING"
CDS_LIB"mstr_standard";
"B \NAC \NWC"3;
"S \NAC"
BN"5"122;
%"TAP"
"6","(-2875,2200)","2","mstr_standard","I113";
;
HDL_TAP"TRUE"
BODY_TYPE"PLUMBING"
CDS_LIB"mstr_standard";
"B \NAC \NWC"3;
"S \NAC"
BN"6"123;
%"TAP"
"6","(-2875,2300)","2","mstr_standard","I114";
;
HDL_TAP"TRUE"
BODY_TYPE"PLUMBING"
CDS_LIB"mstr_standard";
"B \NAC \NWC"3;
"S \NAC"
BN"8"125;
%"TAP"
"6","(-2875,2250)","2","mstr_standard","I115";
;
HDL_TAP"TRUE"
BODY_TYPE"PLUMBING"
CDS_LIB"mstr_standard";
"B \NAC \NWC"3;
"S \NAC"
BN"7"124;
%"TAP"
"6","(-2875,2450)","2","mstr_standard","I116";
;
HDL_TAP"TRUE"
BODY_TYPE"PLUMBING"
CDS_LIB"mstr_standard";
"B \NAC \NWC"3;
"S \NAC"
BN"11"128;
%"TAP"
"6","(-2875,2400)","2","mstr_standard","I117";
;
HDL_TAP"TRUE"
BODY_TYPE"PLUMBING"
CDS_LIB"mstr_standard";
"B \NAC \NWC"3;
"S \NAC"
BN"10"127;
%"TAP"
"6","(-2875,2350)","2","mstr_standard","I118";
;
HDL_TAP"TRUE"
BODY_TYPE"PLUMBING"
CDS_LIB"mstr_standard";
"B \NAC \NWC"3;
"S \NAC"
BN"9"126;
%"TAP"
"6","(-2875,2500)","2","mstr_standard","I119";
;
HDL_TAP"TRUE"
BODY_TYPE"PLUMBING"
CDS_LIB"mstr_standard";
"B \NAC \NWC"3;
"S \NAC"
BN"12"129;
%"TAP"
"6","(-5600,950)","0","mstr_standard","I12";
;
HDL_TAP"TRUE"
BODY_TYPE"PLUMBING"
CDS_LIB"mstr_standard";
"B \NAC \NWC"11;
"S \NAC"
BN"3"36;
%"TAP"
"6","(-2875,2550)","2","mstr_standard","I120";
;
HDL_TAP"TRUE"
BODY_TYPE"PLUMBING"
CDS_LIB"mstr_standard";
"B \NAC \NWC"3;
"S \NAC"
BN"13"130;
%"TAP"
"6","(-2875,2600)","2","mstr_standard","I121";
;
HDL_TAP"TRUE"
BODY_TYPE"PLUMBING"
CDS_LIB"mstr_standard";
"B \NAC \NWC"3;
"S \NAC"
BN"14"131;
%"TAP"
"6","(-2875,2650)","2","mstr_standard","I122";
;
HDL_TAP"TRUE"
BODY_TYPE"PLUMBING"
CDS_LIB"mstr_standard";
"B \NAC \NWC"3;
"S \NAC"
BN"15"132;
%"TAP"
"6","(-2875,2700)","2","mstr_standard","I123";
;
HDL_TAP"TRUE"
BODY_TYPE"PLUMBING"
CDS_LIB"mstr_standard";
"B \NAC \NWC"3;
"S \NAC"
BN"16"133;
%"TAP"
"6","(-2875,2750)","2","mstr_standard","I124";
;
HDL_TAP"TRUE"
BODY_TYPE"PLUMBING"
CDS_LIB"mstr_standard";
"B \NAC \NWC"3;
"S \NAC"
BN"17"134;
%"TAP"
"6","(-2875,2900)","2","mstr_standard","I125";
;
HDL_TAP"TRUE"
BODY_TYPE"PLUMBING"
CDS_LIB"mstr_standard";
"B \NAC \NWC"2;
"S \NAC"
BN"1"142;
%"TAP"
"6","(-2875,2950)","2","mstr_standard","I126";
;
HDL_TAP"TRUE"
BODY_TYPE"PLUMBING"
CDS_LIB"mstr_standard";
"B \NAC \NWC"2;
"S \NAC"
BN"2"143;
%"TAP"
"6","(-2875,2850)","2","mstr_standard","I127";
;
HDL_TAP"TRUE"
BODY_TYPE"PLUMBING"
CDS_LIB"mstr_standard";
"B \NAC \NWC"2;
"S \NAC"
BN"0"141;
%"TAP"
"6","(-2875,3050)","2","mstr_standard","I128";
;
HDL_TAP"TRUE"
BODY_TYPE"PLUMBING"
CDS_LIB"mstr_standard";
"B \NAC \NWC"2;
"S \NAC"
BN"4"145;
%"TAP"
"6","(-2875,3000)","2","mstr_standard","I129";
;
HDL_TAP"TRUE"
BODY_TYPE"PLUMBING"
CDS_LIB"mstr_standard";
"B \NAC \NWC"2;
"S \NAC"
BN"3"144;
%"TAP"
"6","(-5600,1050)","0","mstr_standard","I13";
;
HDL_TAP"TRUE"
BODY_TYPE"PLUMBING"
CDS_LIB"mstr_standard";
"B \NAC \NWC"12;
"S \NAC"
BN"0"14;
%"TAP"
"6","(-2875,3100)","2","mstr_standard","I130";
;
HDL_TAP"TRUE"
BODY_TYPE"PLUMBING"
CDS_LIB"mstr_standard";
"B \NAC \NWC"2;
"S \NAC"
BN"5"146;
%"TAP"
"6","(-2875,3150)","2","mstr_standard","I131";
;
HDL_TAP"TRUE"
BODY_TYPE"PLUMBING"
CDS_LIB"mstr_standard";
"B \NAC \NWC"2;
"S \NAC"
BN"6"147;
%"TAP"
"6","(-2875,3200)","2","mstr_standard","I132";
;
HDL_TAP"TRUE"
BODY_TYPE"PLUMBING"
CDS_LIB"mstr_standard";
"B \NAC \NWC"2;
"S \NAC"
BN"7"148;
%"TAP"
"6","(-2875,3250)","2","mstr_standard","I133";
;
HDL_TAP"TRUE"
BODY_TYPE"PLUMBING"
CDS_LIB"mstr_standard";
"B \NAC \NWC"2;
"S \NAC"
BN"8"149;
%"TAP"
"6","(-2875,3300)","2","mstr_standard","I134";
;
HDL_TAP"TRUE"
BODY_TYPE"PLUMBING"
CDS_LIB"mstr_standard";
"B \NAC \NWC"2;
"S \NAC"
BN"9"150;
%"TAP"
"6","(-2875,3350)","2","mstr_standard","I135";
;
HDL_TAP"TRUE"
BODY_TYPE"PLUMBING"
CDS_LIB"mstr_standard";
"B \NAC \NWC"2;
"S \NAC"
BN"10"151;
%"TAP"
"6","(-2875,3450)","2","mstr_standard","I136";
;
HDL_TAP"TRUE"
BODY_TYPE"PLUMBING"
CDS_LIB"mstr_standard";
"B \NAC \NWC"2;
"S \NAC"
BN"12"153;
%"TAP"
"6","(-2875,3400)","2","mstr_standard","I137";
;
HDL_TAP"TRUE"
BODY_TYPE"PLUMBING"
CDS_LIB"mstr_standard";
"B \NAC \NWC"2;
"S \NAC"
BN"11"152;
%"TAP"
"6","(-2875,3600)","2","mstr_standard","I138";
;
HDL_TAP"TRUE"
BODY_TYPE"PLUMBING"
CDS_LIB"mstr_standard";
"B \NAC \NWC"2;
"S \NAC"
BN"15"156;
%"TAP"
"6","(-2875,3550)","2","mstr_standard","I139";
;
HDL_TAP"TRUE"
BODY_TYPE"PLUMBING"
CDS_LIB"mstr_standard";
"B \NAC \NWC"2;
"S \NAC"
BN"14"155;
%"TAP"
"6","(-5600,1100)","0","mstr_standard","I14";
;
HDL_TAP"TRUE"
BODY_TYPE"PLUMBING"
CDS_LIB"mstr_standard";
"B \NAC \NWC"12;
"S \NAC"
BN"1"15;
%"TAP"
"6","(-2875,3500)","2","mstr_standard","I140";
;
HDL_TAP"TRUE"
BODY_TYPE"PLUMBING"
CDS_LIB"mstr_standard";
"B \NAC \NWC"2;
"S \NAC"
BN"13"154;
%"TAP"
"6","(-2875,3650)","2","mstr_standard","I141";
;
HDL_TAP"TRUE"
BODY_TYPE"PLUMBING"
CDS_LIB"mstr_standard";
"B \NAC \NWC"2;
"S \NAC"
BN"16"157;
%"TAP"
"6","(-2875,3700)","2","mstr_standard","I142";
;
HDL_TAP"TRUE"
BODY_TYPE"PLUMBING"
CDS_LIB"mstr_standard";
"B \NAC \NWC"2;
"S \NAC"
BN"17"158;
%"TAP"
"6","(-2875,3800)","2","mstr_standard","I143";
;
HDL_TAP"TRUE"
BODY_TYPE"PLUMBING"
CDS_LIB"mstr_standard";
"B \NAC \NWC"1;
"S \NAC"
BN"0"135;
%"TAP"
"6","(-2875,3850)","2","mstr_standard","I144";
;
HDL_TAP"TRUE"
BODY_TYPE"PLUMBING"
CDS_LIB"mstr_standard";
"B \NAC \NWC"1;
"S \NAC"
BN"1"136;
%"TAP"
"6","(-2875,3900)","2","mstr_standard","I145";
;
HDL_TAP"TRUE"
BODY_TYPE"PLUMBING"
CDS_LIB"mstr_standard";
"B \NAC \NWC"1;
"S \NAC"
BN"2"137;
%"TAP"
"6","(-2875,3950)","2","mstr_standard","I146";
;
HDL_TAP"TRUE"
BODY_TYPE"PLUMBING"
CDS_LIB"mstr_standard";
"B \NAC \NWC"1;
"S \NAC"
BN"3"138;
%"TAP"
"6","(-5600,1150)","0","mstr_standard","I15";
;
HDL_TAP"TRUE"
BODY_TYPE"PLUMBING"
CDS_LIB"mstr_standard";
"B \NAC \NWC"12;
"S \NAC"
BN"2"16;
%"TAP"
"6","(-2875,4000)","2","mstr_standard","I157";
;
HDL_TAP"TRUE"
BODY_TYPE"PLUMBING"
CDS_LIB"mstr_standard";
"B \NAC \NWC"1;
"S \NAC"
BN"4"139;
%"TAP"
"6","(-2875,4100)","2","mstr_standard","I158";
;
HDL_TAP"TRUE"
BODY_TYPE"PLUMBING"
CDS_LIB"mstr_standard";
"B \NAC \NWC"1;
"S \NAC"
BN"6"159;
%"TAP"
"6","(-2875,4050)","2","mstr_standard","I159";
;
HDL_TAP"TRUE"
BODY_TYPE"PLUMBING"
CDS_LIB"mstr_standard";
"B \NAC \NWC"1;
"S \NAC"
BN"5"140;
%"TAP"
"6","(-5600,1250)","0","mstr_standard","I16";
;
HDL_TAP"TRUE"
BODY_TYPE"PLUMBING"
CDS_LIB"mstr_standard";
"B \NAC \NWC"12;
"S \NAC"
BN"4"18;
%"TAP"
"6","(-2875,4150)","2","mstr_standard","I160";
;
HDL_TAP"TRUE"
BODY_TYPE"PLUMBING"
CDS_LIB"mstr_standard";
"B \NAC \NWC"1;
"S \NAC"
BN"7"160;
%"TAP"
"6","(-2875,4200)","2","mstr_standard","I161";
;
HDL_TAP"TRUE"
BODY_TYPE"PLUMBING"
CDS_LIB"mstr_standard";
"B \NAC \NWC"1;
"S \NAC"
BN"8"161;
%"TAP"
"6","(-2875,4250)","2","mstr_standard","I162";
;
HDL_TAP"TRUE"
BODY_TYPE"PLUMBING"
CDS_LIB"mstr_standard";
"B \NAC \NWC"1;
"S \NAC"
BN"9"162;
%"TAP"
"6","(-2875,4300)","2","mstr_standard","I163";
;
HDL_TAP"TRUE"
BODY_TYPE"PLUMBING"
CDS_LIB"mstr_standard";
"B \NAC \NWC"1;
"S \NAC"
BN"10"163;
%"TAP"
"6","(-2875,4350)","2","mstr_standard","I164";
;
HDL_TAP"TRUE"
BODY_TYPE"PLUMBING"
CDS_LIB"mstr_standard";
"B \NAC \NWC"1;
"S \NAC"
BN"11"164;
%"TAP"
"6","(-2875,4500)","2","mstr_standard","I165";
;
HDL_TAP"TRUE"
BODY_TYPE"PLUMBING"
CDS_LIB"mstr_standard";
"B \NAC \NWC"1;
"S \NAC"
BN"14"167;
%"TAP"
"6","(-2875,4450)","2","mstr_standard","I166";
;
HDL_TAP"TRUE"
BODY_TYPE"PLUMBING"
CDS_LIB"mstr_standard";
"B \NAC \NWC"1;
"S \NAC"
BN"13"166;
%"TAP"
"6","(-2875,4400)","2","mstr_standard","I167";
;
HDL_TAP"TRUE"
BODY_TYPE"PLUMBING"
CDS_LIB"mstr_standard";
"B \NAC \NWC"1;
"S \NAC"
BN"12"165;
%"TAP"
"6","(-2875,4550)","2","mstr_standard","I168";
;
HDL_TAP"TRUE"
BODY_TYPE"PLUMBING"
CDS_LIB"mstr_standard";
"B \NAC \NWC"1;
"S \NAC"
BN"15"168;
%"TAP"
"6","(-2875,4600)","2","mstr_standard","I169";
;
HDL_TAP"TRUE"
BODY_TYPE"PLUMBING"
CDS_LIB"mstr_standard";
"B \NAC \NWC"1;
"S \NAC"
BN"16"169;
%"TAP"
"6","(-5600,1200)","0","mstr_standard","I17";
;
HDL_TAP"TRUE"
BODY_TYPE"PLUMBING"
CDS_LIB"mstr_standard";
"B \NAC \NWC"12;
"S \NAC"
BN"3"17;
%"TAP"
"6","(-2875,4650)","2","mstr_standard","I170";
;
HDL_TAP"TRUE"
BODY_TYPE"PLUMBING"
CDS_LIB"mstr_standard";
"B \NAC \NWC"1;
"S \NAC"
BN"17"170;
%"SKX_EXT_B"
"8","(-4200,2550)","0","chpset_lib","I172";
;
CDS_SEC"8"
CDS_LOCATION"U2D1"
SEC"8"
CDS_LIB"chpset_lib"
SEC_TYPE"BGA1"
PACK_TYPE"BGA1"
MATERIAL"IC"
PART_NUMBER"TBD"
LOCATION"U2D1";
"DDR5_PAR"
$PN"DK53"117;
"DDR5_ODT<0>"
$PN"DG50"94;
"DDR5_ODT<1>"
$PN"DG48"95;
"DDR5_ODT<2>"
$PN"DK49"96;
"DDR5_ODT<3>"
$PN"DF47"97;
"DDR5_MA<0>"
$PN"DF53"98;
"DDR5_MA<1>"
$PN"DC58"99;
"DDR5_MA<2>"
$PN"DD57"100;
"DDR5_MA<3>"
$PN"DG58"120;
"DDR5_MA<4>"
$PN"DJ58"121;
"DDR5_MA<5>"
$PN"DF59"122;
"DDR5_MA<6>"
$PN"DK59"123;
"DDR5_MA<7>"
$PN"DC60"124;
"DDR5_MA<8>"
$PN"DD59"125;
"DDR5_MA<9>"
$PN"DA58"126;
"DDR5_MA<10>"
$PN"DD55"127;
"DDR5_MA<11>"
$PN"DA60"128;
"DDR5_MA<12>"
$PN"DG60"129;
"DDR5_MA<13>"
$PN"DD53"130;
"DDR5_MA<14>"
$PN"DJ50"131;
"DDR5_MA<15>"
$PN"DC54"132;
"DDR5_MA<16>"
$PN"DG52"133;
"DDR5_MA<17>"
$PN"DE46"134;
"DDR5_ECC<0>"
$PN"CH71"14;
"DDR5_ECC<1>"
$PN"CM71"15;
"DDR5_ECC<2>"
$PN"CJ68"16;
"DDR5_ECC<3>"
$PN"CL68"17;
"DDR5_ECC<4>"
$PN"CJ72"18;
"DDR5_ECC<5>"
$PN"CL72"19;
"DDR5_ECC<6>"
$PN"CH69"20;
"DDR5_ECC<7>"
$PN"CM69"21;
"DDR5_DQS_DP<0>"
$PN"CR76"135;
"DDR5_DQS_DP<1>"
$PN"DE76"136;
"DDR5_DQS_DP<2>"
$PN"DK71"137;
"DDR5_DQS_DP<3>"
$PN"CT65"138;
"DDR5_DQS_DP<4>"
$PN"DJ40"139;
"DDR5_DQS_DP<5>"
$PN"DJ32"140;
"DDR5_DQS_DP<6>"
$PN"DB35"159;
"DDR5_DQS_DP<7>"
$PN"DB29"160;
"DDR5_DQS_DP<8>"
$PN"CL70"161;
"DDR5_DQS_DP<9>"
$PN"CU74"162;
"DDR5_DQS_DP<10>"
$PN"DG74"163;
"DDR5_DQS_DP<11>"
$PN"DH69"164;
"DDR5_DQS_DP<12>"
$PN"CM65"165;
"DDR5_DQS_DP<13>"
$PN"DC40"166;
"DDR5_DQS_DP<14>"
$PN"DE32"167;
"DDR5_DQS_DP<15>"
$PN"CV35"168;
"DDR5_DQS_DP<16>"
$PN"CV29"169;
"DDR5_DQS_DP<17>"
$PN"CG70"170;
"DDR5_DQS_DN<0>"
$PN"CP77"141;
"DDR5_DQS_DN<1>"
$PN"DD77"142;
"DDR5_DQS_DN<2>"
$PN"DL72"143;
"DDR5_DQS_DN<3>"
$PN"CV65"144;
"DDR5_DQS_DN<4>"
$PN"DG40"145;
"DDR5_DQS_DN<5>"
$PN"DL32"146;
"DDR5_DQS_DN<6>"
$PN"DD35"147;
"DDR5_DQS_DN<7>"
$PN"DD29"148;
"DDR5_DQS_DN<8>"
$PN"CN70"149;
"DDR5_DQS_DN<9>"
$PN"CT75"150;
"DDR5_DQS_DN<10>"
$PN"DF75"151;
"DDR5_DQS_DN<11>"
$PN"DJ70"152;
"DDR5_DQS_DN<12>"
$PN"CP65"153;
"DDR5_DQS_DN<13>"
$PN"DE40"154;
"DDR5_DQS_DN<14>"
$PN"DG32"155;
"DDR5_DQS_DN<15>"
$PN"CY35"156;
"DDR5_DQS_DN<16>"
$PN"CY29"157;
"DDR5_DQS_DN<17>"
$PN"CJ70"158;
"DDR5_DQ<0>"
$PN"CR74"22;
"DDR5_DQ<1>"
$PN"CN76"23;
"DDR5_DQ<2>"
$PN"CW76"24;
"DDR5_DQ<3>"
$PN"CV77"25;
"DDR5_DQ<4>"
$PN"CN74"26;
"DDR5_DQ<5>"
$PN"CM75"27;
"DDR5_DQ<6>"
$PN"CV75"28;
"DDR5_DQ<7>"
$PN"CT77"29;
"DDR5_DQ<8>"
$PN"DE74"30;
"DDR5_DQ<9>"
$PN"DC76"31;
"DDR5_DQ<10>"
$PN"DH75"32;
"DDR5_DQ<11>"
$PN"DJ76"41;
"DDR5_DQ<12>"
$PN"DC74"42;
"DDR5_DQ<13>"
$PN"DB75"43;
"DDR5_DQ<14>"
$PN"DF77"44;
"DDR5_DQ<15>"
$PN"DH77"45;
"DDR5_DQ<16>"
$PN"DG70"46;
"DDR5_DQ<17>"
$PN"DJ72"47;
"DDR5_DQ<18>"
$PN"DM69"48;
"DDR5_DQ<19>"
$PN"DN70"49;
"DDR5_DQ<20>"
$PN"DF71"50;
"DDR5_DQ<21>"
$PN"DG72"51;
"DDR5_DQ<22>"
$PN"DK69"52;
"DDR5_DQ<23>"
$PN"DM71"53;
"DDR5_DQ<24>"
$PN"CN66"54;
"DDR5_DQ<25>"
$PN"CU66"55;
"DDR5_DQ<26>"
$PN"CP63"56;
"DDR5_DQ<27>"
$PN"CT63"57;
"DDR5_DQ<28>"
$PN"CP67"58;
"DDR5_DQ<29>"
$PN"CT67"59;
"DDR5_DQ<30>"
$PN"CN64"60;
"DDR5_DQ<31>"
$PN"CU64"61;
"DDR5_DQ<32>"
$PN"DD41"62;
"DDR5_DQ<33>"
$PN"DG42"63;
"DDR5_DQ<34>"
$PN"DE38"64;
"DDR5_DQ<35>"
$PN"DG38"65;
"DDR5_DQ<36>"
$PN"DA42"66;
"DDR5_DQ<37>"
$PN"DE42"67;
"DDR5_DQ<38>"
$PN"DD39"68;
"DDR5_DQ<39>"
$PN"DH39"69;
"DDR5_DQ<40>"
$PN"DF33"70;
"DDR5_DQ<41>"
$PN"DK33"71;
"DDR5_DQ<42>"
$PN"DG30"72;
"DDR5_DQ<43>"
$PN"DJ30"73;
"DDR5_DQ<44>"
$PN"DG34"74;
"DDR5_DQ<45>"
$PN"DJ34"75;
"DDR5_DQ<46>"
$PN"DF31"76;
"DDR5_DQ<47>"
$PN"DK31"77;
"DDR5_DQ<48>"
$PN"CW36"78;
"DDR5_DQ<49>"
$PN"DC36"79;
"DDR5_DQ<50>"
$PN"CY33"80;
"DDR5_DQ<51>"
$PN"DB33"81;
"DDR5_DQ<52>"
$PN"CY37"82;
"DDR5_DQ<53>"
$PN"DB37"83;
"DDR5_DQ<54>"
$PN"CW34"84;
"DDR5_DQ<55>"
$PN"DC34"85;
"DDR5_DQ<56>"
$PN"CW30"86;
"DDR5_DQ<57>"
$PN"DC30"87;
"DDR5_DQ<58>"
$PN"CY27"88;
"DDR5_DQ<59>"
$PN"DB27"89;
"DDR5_DQ<60>"
$PN"CY31"90;
"DDR5_DQ<61>"
$PN"DB31"91;
"DDR5_DQ<62>"
$PN"CW28"92;
"DDR5_DQ<63>"
$PN"DC28"93;
"DDR5_CS_N<0>"
$PN"DK51"101;
"DDR5_CS_N<1>"
$PN"DF49"102;
"DDR5_CS_N<2>"
$PN"DJ46"103;
"DDR5_CS_N<3>"
$PN"DG46"104;
"DDR5_CS_N<4>"
$PN"DF51"105;
"DDR5_CS_N<5>"
$PN"DJ48"106;
"DDR5_CS_N<6>"
$PN"DM45"107;
"DDR5_CS_N<7>"
$PN"DK45"108;
"DDR5_CLK_DP<0>"
$PN"DJ54"33;
"DDR5_CLK_DP<1>"
$PN"DG54"34;
"DDR5_CLK_DP<2>"
$PN"DJ56"35;
"DDR5_CLK_DP<3>"
$PN"DG56"36;
"DDR5_CLK_DN<0>"
$PN"DK55"37;
"DDR5_CLK_DN<1>"
$PN"DF55"38;
"DDR5_CLK_DN<2>"
$PN"DK57"39;
"DDR5_CLK_DN<3>"
$PN"DF57"40;
"DDR5_CKE<0>"
$PN"DG62"109;
"DDR5_CKE<1>"
$PN"DD63"110;
"DDR5_CKE<2>"
$PN"DK63"111;
"DDR5_CKE<3>"
$PN"DF63"112;
"DDR5_CID<2>"
$PN"DF45"13;
"DDR5_BG<0>"
$PN"DA62"113;
"DDR5_BG<1>"
$PN"DF61"114;
"DDR5_BA<0>"
$PN"DJ52"115;
"DDR5_BA<1>"
$PN"DC56"116;
"DDR5_ALERT_N"
$PN"DD61"119;
"DDR5_ACT_N"
$PN"DC62"118;
%"TAP"
"6","(-5600,1300)","0","mstr_standard","I18";
;
HDL_TAP"TRUE"
BODY_TYPE"PLUMBING"
CDS_LIB"mstr_standard";
"B \NAC \NWC"12;
"S \NAC"
BN"5"19;
%"TAP"
"6","(-5600,1350)","0","mstr_standard","I19";
;
HDL_TAP"TRUE"
BODY_TYPE"PLUMBING"
CDS_LIB"mstr_standard";
"B \NAC \NWC"12;
"S \NAC"
BN"6"20;
%"TAP"
"6","(-5600,1400)","0","mstr_standard","I20";
;
HDL_TAP"TRUE"
BODY_TYPE"PLUMBING"
CDS_LIB"mstr_standard";
"B \NAC \NWC"12;
"S \NAC"
BN"7"21;
%"TAP"
"6","(-5600,1500)","0","mstr_standard","I21";
;
HDL_TAP"TRUE"
BODY_TYPE"PLUMBING"
CDS_LIB"mstr_standard";
"B \NAC \NWC"9;
"S \NAC"
BN"0"22;
%"TAP"
"6","(-5600,1550)","0","mstr_standard","I22";
;
HDL_TAP"TRUE"
BODY_TYPE"PLUMBING"
CDS_LIB"mstr_standard";
"B \NAC \NWC"9;
"S \NAC"
BN"1"23;
%"TAP"
"6","(-5600,1600)","0","mstr_standard","I23";
;
HDL_TAP"TRUE"
BODY_TYPE"PLUMBING"
CDS_LIB"mstr_standard";
"B \NAC \NWC"9;
"S \NAC"
BN"2"24;
%"TAP"
"6","(-5600,1650)","0","mstr_standard","I24";
;
HDL_TAP"TRUE"
BODY_TYPE"PLUMBING"
CDS_LIB"mstr_standard";
"B \NAC \NWC"9;
"S \NAC"
BN"3"25;
%"TAP"
"6","(-5600,1700)","0","mstr_standard","I25";
;
HDL_TAP"TRUE"
BODY_TYPE"PLUMBING"
CDS_LIB"mstr_standard";
"B \NAC \NWC"9;
"S \NAC"
BN"4"26;
%"TAP"
"6","(-5600,1750)","0","mstr_standard","I26";
;
HDL_TAP"TRUE"
BODY_TYPE"PLUMBING"
CDS_LIB"mstr_standard";
"B \NAC \NWC"9;
"S \NAC"
BN"5"27;
%"TAP"
"6","(-5600,1800)","0","mstr_standard","I27";
;
HDL_TAP"TRUE"
BODY_TYPE"PLUMBING"
CDS_LIB"mstr_standard";
"B \NAC \NWC"9;
"S \NAC"
BN"6"28;
%"TAP"
"6","(-5600,1900)","0","mstr_standard","I28";
;
HDL_TAP"TRUE"
BODY_TYPE"PLUMBING"
CDS_LIB"mstr_standard";
"B \NAC \NWC"9;
"S \NAC"
BN"8"30;
%"TAP"
"6","(-5600,1850)","0","mstr_standard","I29";
;
HDL_TAP"TRUE"
BODY_TYPE"PLUMBING"
CDS_LIB"mstr_standard";
"B \NAC \NWC"9;
"S \NAC"
BN"7"29;
%"TAP"
"6","(-5600,1950)","0","mstr_standard","I31";
;
HDL_TAP"TRUE"
BODY_TYPE"PLUMBING"
CDS_LIB"mstr_standard";
"B \NAC \NWC"9;
"S \NAC"
BN"9"31;
%"TAP"
"6","(-5600,2000)","0","mstr_standard","I32";
;
HDL_TAP"TRUE"
BODY_TYPE"PLUMBING"
CDS_LIB"mstr_standard";
"B \NAC \NWC"9;
"S \NAC"
BN"10"32;
%"TAP"
"6","(-5600,2050)","0","mstr_standard","I33";
;
HDL_TAP"TRUE"
BODY_TYPE"PLUMBING"
CDS_LIB"mstr_standard";
"B \NAC \NWC"9;
"S \NAC"
BN"11"41;
%"TAP"
"6","(-5600,2100)","0","mstr_standard","I34";
;
HDL_TAP"TRUE"
BODY_TYPE"PLUMBING"
CDS_LIB"mstr_standard";
"B \NAC \NWC"9;
"S \NAC"
BN"12"42;
%"TAP"
"6","(-5600,2150)","0","mstr_standard","I35";
;
HDL_TAP"TRUE"
BODY_TYPE"PLUMBING"
CDS_LIB"mstr_standard";
"B \NAC \NWC"9;
"S \NAC"
BN"13"43;
%"TAP"
"6","(-5600,2200)","0","mstr_standard","I36";
;
HDL_TAP"TRUE"
BODY_TYPE"PLUMBING"
CDS_LIB"mstr_standard";
"B \NAC \NWC"9;
"S \NAC"
BN"14"44;
%"TAP"
"6","(-5600,2250)","0","mstr_standard","I37";
;
HDL_TAP"TRUE"
BODY_TYPE"PLUMBING"
CDS_LIB"mstr_standard";
"B \NAC \NWC"9;
"S \NAC"
BN"15"45;
%"TAP"
"6","(-5600,2300)","0","mstr_standard","I38";
;
HDL_TAP"TRUE"
BODY_TYPE"PLUMBING"
CDS_LIB"mstr_standard";
"B \NAC \NWC"9;
"S \NAC"
BN"16"46;
%"TAP"
"6","(-5600,2350)","0","mstr_standard","I39";
;
HDL_TAP"TRUE"
BODY_TYPE"PLUMBING"
CDS_LIB"mstr_standard";
"B \NAC \NWC"9;
"S \NAC"
BN"17"47;
%"TAP"
"6","(-5600,2400)","0","mstr_standard","I40";
;
HDL_TAP"TRUE"
BODY_TYPE"PLUMBING"
CDS_LIB"mstr_standard";
"B \NAC \NWC"9;
"S \NAC"
BN"18"48;
%"TAP"
"6","(-5600,2450)","0","mstr_standard","I41";
;
HDL_TAP"TRUE"
BODY_TYPE"PLUMBING"
CDS_LIB"mstr_standard";
"B \NAC \NWC"9;
"S \NAC"
BN"19"49;
%"TAP"
"6","(-5600,2500)","0","mstr_standard","I42";
;
HDL_TAP"TRUE"
BODY_TYPE"PLUMBING"
CDS_LIB"mstr_standard";
"B \NAC \NWC"9;
"S \NAC"
BN"20"50;
%"TAP"
"6","(-5600,2550)","0","mstr_standard","I43";
;
HDL_TAP"TRUE"
BODY_TYPE"PLUMBING"
CDS_LIB"mstr_standard";
"B \NAC \NWC"9;
"S \NAC"
BN"21"51;
%"TAP"
"6","(-5600,2600)","0","mstr_standard","I44";
;
HDL_TAP"TRUE"
BODY_TYPE"PLUMBING"
CDS_LIB"mstr_standard";
"B \NAC \NWC"9;
"S \NAC"
BN"22"52;
%"TAP"
"6","(-5600,2650)","0","mstr_standard","I45";
;
HDL_TAP"TRUE"
BODY_TYPE"PLUMBING"
CDS_LIB"mstr_standard";
"B \NAC \NWC"9;
"S \NAC"
BN"23"53;
%"TAP"
"6","(-5600,2700)","0","mstr_standard","I46";
;
HDL_TAP"TRUE"
BODY_TYPE"PLUMBING"
CDS_LIB"mstr_standard";
"B \NAC \NWC"9;
"S \NAC"
BN"24"54;
%"TAP"
"6","(-5600,2800)","0","mstr_standard","I47";
;
HDL_TAP"TRUE"
BODY_TYPE"PLUMBING"
CDS_LIB"mstr_standard";
"B \NAC \NWC"9;
"S \NAC"
BN"26"56;
%"TAP"
"6","(-5600,2750)","0","mstr_standard","I48";
;
HDL_TAP"TRUE"
BODY_TYPE"PLUMBING"
CDS_LIB"mstr_standard";
"B \NAC \NWC"9;
"S \NAC"
BN"25"55;
%"TAP"
"6","(-5600,2850)","0","mstr_standard","I49";
;
HDL_TAP"TRUE"
BODY_TYPE"PLUMBING"
CDS_LIB"mstr_standard";
"B \NAC \NWC"9;
"S \NAC"
BN"27"57;
%"TAP"
"6","(-5600,600)","0","mstr_standard","I5";
;
HDL_TAP"TRUE"
BODY_TYPE"PLUMBING"
CDS_LIB"mstr_standard";
"B \NAC \NWC"10;
"S \NAC"
BN"0"37;
%"TAP"
"6","(-5600,2900)","0","mstr_standard","I50";
;
HDL_TAP"TRUE"
BODY_TYPE"PLUMBING"
CDS_LIB"mstr_standard";
"B \NAC \NWC"9;
"S \NAC"
BN"28"58;
%"TAP"
"6","(-5600,2950)","0","mstr_standard","I51";
;
HDL_TAP"TRUE"
BODY_TYPE"PLUMBING"
CDS_LIB"mstr_standard";
"B \NAC \NWC"9;
"S \NAC"
BN"29"59;
%"TAP"
"6","(-5600,3050)","0","mstr_standard","I52";
;
HDL_TAP"TRUE"
BODY_TYPE"PLUMBING"
CDS_LIB"mstr_standard";
"B \NAC \NWC"9;
"S \NAC"
BN"31"61;
%"TAP"
"6","(-5600,3000)","0","mstr_standard","I53";
;
HDL_TAP"TRUE"
BODY_TYPE"PLUMBING"
CDS_LIB"mstr_standard";
"B \NAC \NWC"9;
"S \NAC"
BN"30"60;
%"TAP"
"6","(-5600,3100)","0","mstr_standard","I54";
;
HDL_TAP"TRUE"
BODY_TYPE"PLUMBING"
CDS_LIB"mstr_standard";
"B \NAC \NWC"9;
"S \NAC"
BN"32"62;
%"TAP"
"6","(-5600,3150)","0","mstr_standard","I55";
;
HDL_TAP"TRUE"
BODY_TYPE"PLUMBING"
CDS_LIB"mstr_standard";
"B \NAC \NWC"9;
"S \NAC"
BN"33"63;
%"TAP"
"6","(-5600,3200)","0","mstr_standard","I56";
;
HDL_TAP"TRUE"
BODY_TYPE"PLUMBING"
CDS_LIB"mstr_standard";
"B \NAC \NWC"9;
"S \NAC"
BN"34"64;
%"TAP"
"6","(-5600,3300)","0","mstr_standard","I57";
;
HDL_TAP"TRUE"
BODY_TYPE"PLUMBING"
CDS_LIB"mstr_standard";
"B \NAC \NWC"9;
"S \NAC"
BN"36"66;
%"TAP"
"6","(-5600,3250)","0","mstr_standard","I58";
;
HDL_TAP"TRUE"
BODY_TYPE"PLUMBING"
CDS_LIB"mstr_standard";
"B \NAC \NWC"9;
"S \NAC"
BN"35"65;
%"TAP"
"6","(-5600,3350)","0","mstr_standard","I59";
;
HDL_TAP"TRUE"
BODY_TYPE"PLUMBING"
CDS_LIB"mstr_standard";
"B \NAC \NWC"9;
"S \NAC"
BN"37"67;
%"TAP"
"6","(-5600,650)","0","mstr_standard","I6";
;
HDL_TAP"TRUE"
BODY_TYPE"PLUMBING"
CDS_LIB"mstr_standard";
"B \NAC \NWC"10;
"S \NAC"
BN"1"38;
%"TAP"
"6","(-5600,3400)","0","mstr_standard","I60";
;
HDL_TAP"TRUE"
BODY_TYPE"PLUMBING"
CDS_LIB"mstr_standard";
"B \NAC \NWC"9;
"S \NAC"
BN"38"68;
%"TAP"
"6","(-5600,3450)","0","mstr_standard","I61";
;
HDL_TAP"TRUE"
BODY_TYPE"PLUMBING"
CDS_LIB"mstr_standard";
"B \NAC \NWC"9;
"S \NAC"
BN"39"69;
%"TAP"
"6","(-5600,3500)","0","mstr_standard","I62";
;
HDL_TAP"TRUE"
BODY_TYPE"PLUMBING"
CDS_LIB"mstr_standard";
"B \NAC \NWC"9;
"S \NAC"
BN"40"70;
%"TAP"
"6","(-5600,3550)","0","mstr_standard","I63";
;
HDL_TAP"TRUE"
BODY_TYPE"PLUMBING"
CDS_LIB"mstr_standard";
"B \NAC \NWC"9;
"S \NAC"
BN"41"71;
%"TAP"
"6","(-5600,3600)","0","mstr_standard","I64";
;
HDL_TAP"TRUE"
BODY_TYPE"PLUMBING"
CDS_LIB"mstr_standard";
"B \NAC \NWC"9;
"S \NAC"
BN"42"72;
%"TAP"
"6","(-5600,3650)","0","mstr_standard","I65";
;
HDL_TAP"TRUE"
BODY_TYPE"PLUMBING"
CDS_LIB"mstr_standard";
"B \NAC \NWC"9;
"S \NAC"
BN"43"73;
%"TAP"
"6","(-5600,3700)","0","mstr_standard","I66";
;
HDL_TAP"TRUE"
BODY_TYPE"PLUMBING"
CDS_LIB"mstr_standard";
"B \NAC \NWC"9;
"S \NAC"
BN"44"74;
%"TAP"
"6","(-5600,3750)","0","mstr_standard","I67";
;
HDL_TAP"TRUE"
BODY_TYPE"PLUMBING"
CDS_LIB"mstr_standard";
"B \NAC \NWC"9;
"S \NAC"
BN"45"75;
%"TAP"
"6","(-5600,3800)","0","mstr_standard","I68";
;
HDL_TAP"TRUE"
BODY_TYPE"PLUMBING"
CDS_LIB"mstr_standard";
"B \NAC \NWC"9;
"S \NAC"
BN"46"76;
%"TAP"
"6","(-5600,3850)","0","mstr_standard","I69";
;
HDL_TAP"TRUE"
BODY_TYPE"PLUMBING"
CDS_LIB"mstr_standard";
"B \NAC \NWC"9;
"S \NAC"
BN"47"77;
%"TAP"
"6","(-5600,750)","0","mstr_standard","I7";
;
HDL_TAP"TRUE"
BODY_TYPE"PLUMBING"
CDS_LIB"mstr_standard";
"B \NAC \NWC"10;
"S \NAC"
BN"3"40;
%"TAP"
"6","(-5600,3900)","0","mstr_standard","I70";
;
HDL_TAP"TRUE"
BODY_TYPE"PLUMBING"
CDS_LIB"mstr_standard";
"B \NAC \NWC"9;
"S \NAC"
BN"48"78;
%"TAP"
"6","(-5600,3950)","0","mstr_standard","I71";
;
HDL_TAP"TRUE"
BODY_TYPE"PLUMBING"
CDS_LIB"mstr_standard";
"B \NAC \NWC"9;
"S \NAC"
BN"49"79;
%"TAP"
"6","(-5600,4000)","0","mstr_standard","I73";
;
HDL_TAP"TRUE"
BODY_TYPE"PLUMBING"
CDS_LIB"mstr_standard";
"B \NAC \NWC"9;
"S \NAC"
BN"50"80;
%"TAP"
"6","(-5600,4050)","0","mstr_standard","I74";
;
HDL_TAP"TRUE"
BODY_TYPE"PLUMBING"
CDS_LIB"mstr_standard";
"B \NAC \NWC"9;
"S \NAC"
BN"51"81;
%"TAP"
"6","(-5600,4100)","0","mstr_standard","I75";
;
HDL_TAP"TRUE"
BODY_TYPE"PLUMBING"
CDS_LIB"mstr_standard";
"B \NAC \NWC"9;
"S \NAC"
BN"52"82;
%"TAP"
"6","(-5600,4150)","0","mstr_standard","I76";
;
HDL_TAP"TRUE"
BODY_TYPE"PLUMBING"
CDS_LIB"mstr_standard";
"B \NAC \NWC"9;
"S \NAC"
BN"53"83;
%"TAP"
"6","(-5600,4200)","0","mstr_standard","I77";
;
HDL_TAP"TRUE"
BODY_TYPE"PLUMBING"
CDS_LIB"mstr_standard";
"B \NAC \NWC"9;
"S \NAC"
BN"54"84;
%"TAP"
"6","(-5600,4250)","0","mstr_standard","I78";
;
HDL_TAP"TRUE"
BODY_TYPE"PLUMBING"
CDS_LIB"mstr_standard";
"B \NAC \NWC"9;
"S \NAC"
BN"55"85;
%"TAP"
"6","(-5600,4300)","0","mstr_standard","I79";
;
HDL_TAP"TRUE"
BODY_TYPE"PLUMBING"
CDS_LIB"mstr_standard";
"B \NAC \NWC"9;
"S \NAC"
BN"56"86;
%"TAP"
"6","(-5600,700)","0","mstr_standard","I8";
;
HDL_TAP"TRUE"
BODY_TYPE"PLUMBING"
CDS_LIB"mstr_standard";
"B \NAC \NWC"10;
"S \NAC"
BN"2"39;
%"TAP"
"6","(-5600,4350)","0","mstr_standard","I80";
;
HDL_TAP"TRUE"
BODY_TYPE"PLUMBING"
CDS_LIB"mstr_standard";
"B \NAC \NWC"9;
"S \NAC"
BN"57"87;
%"TAP"
"6","(-5600,4400)","0","mstr_standard","I81";
;
HDL_TAP"TRUE"
BODY_TYPE"PLUMBING"
CDS_LIB"mstr_standard";
"B \NAC \NWC"9;
"S \NAC"
BN"58"88;
%"TAP"
"6","(-5600,4450)","0","mstr_standard","I82";
;
HDL_TAP"TRUE"
BODY_TYPE"PLUMBING"
CDS_LIB"mstr_standard";
"B \NAC \NWC"9;
"S \NAC"
BN"59"89;
%"TAP"
"6","(-5600,4500)","0","mstr_standard","I83";
;
HDL_TAP"TRUE"
BODY_TYPE"PLUMBING"
CDS_LIB"mstr_standard";
"B \NAC \NWC"9;
"S \NAC"
BN"60"90;
%"TAP"
"6","(-5600,4550)","0","mstr_standard","I84";
;
HDL_TAP"TRUE"
BODY_TYPE"PLUMBING"
CDS_LIB"mstr_standard";
"B \NAC \NWC"9;
"S \NAC"
BN"61"91;
%"TAP"
"6","(-5600,4600)","0","mstr_standard","I85";
;
HDL_TAP"TRUE"
BODY_TYPE"PLUMBING"
CDS_LIB"mstr_standard";
"B \NAC \NWC"9;
"S \NAC"
BN"62"92;
%"TAP"
"6","(-5600,4650)","0","mstr_standard","I86";
;
HDL_TAP"TRUE"
BODY_TYPE"PLUMBING"
CDS_LIB"mstr_standard";
"B \NAC \NWC"9;
"S \NAC"
BN"63"93;
%"TAP"
"6","(-2875,750)","2","mstr_standard","I87";
;
HDL_TAP"TRUE"
BODY_TYPE"PLUMBING"
CDS_LIB"mstr_standard";
"B \NAC \NWC"4;
"S \NAC"
BN"1"116;
%"TAP"
"6","(-2875,700)","2","mstr_standard","I88";
;
HDL_TAP"TRUE"
BODY_TYPE"PLUMBING"
CDS_LIB"mstr_standard";
"B \NAC \NWC"4;
"S \NAC"
BN"0"115;
%"TAP"
"6","(-2875,800)","2","mstr_standard","I89";
;
HDL_TAP"TRUE"
BODY_TYPE"PLUMBING"
CDS_LIB"mstr_standard";
"B \NAC \NWC"5;
"S \NAC"
BN"0"113;
%"TAP"
"6","(-5600,850)","0","mstr_standard","I9";
;
HDL_TAP"TRUE"
BODY_TYPE"PLUMBING"
CDS_LIB"mstr_standard";
"B \NAC \NWC"11;
"S \NAC"
BN"1"34;
%"TAP"
"6","(-2875,850)","2","mstr_standard","I90";
;
HDL_TAP"TRUE"
BODY_TYPE"PLUMBING"
CDS_LIB"mstr_standard";
"B \NAC \NWC"5;
"S \NAC"
BN"1"114;
%"TAP"
"6","(-2875,1050)","2","mstr_standard","I91";
;
HDL_TAP"TRUE"
BODY_TYPE"PLUMBING"
CDS_LIB"mstr_standard";
"B \NAC \NWC"7;
"S \NAC"
BN"2"103;
%"TAP"
"6","(-2875,1000)","2","mstr_standard","I92";
;
HDL_TAP"TRUE"
BODY_TYPE"PLUMBING"
CDS_LIB"mstr_standard";
"B \NAC \NWC"7;
"S \NAC"
BN"1"102;
%"TAP"
"6","(-2875,950)","2","mstr_standard","I93";
;
HDL_TAP"TRUE"
BODY_TYPE"PLUMBING"
CDS_LIB"mstr_standard";
"B \NAC \NWC"7;
"S \NAC"
BN"0"101;
%"TAP"
"6","(-2875,1150)","2","mstr_standard","I94";
;
HDL_TAP"TRUE"
BODY_TYPE"PLUMBING"
CDS_LIB"mstr_standard";
"B \NAC \NWC"7;
"S \NAC"
BN"4"105;
%"TAP"
"6","(-2875,1100)","2","mstr_standard","I95";
;
HDL_TAP"TRUE"
BODY_TYPE"PLUMBING"
CDS_LIB"mstr_standard";
"B \NAC \NWC"7;
"S \NAC"
BN"3"104;
%"TAP"
"6","(-2875,1200)","2","mstr_standard","I96";
;
HDL_TAP"TRUE"
BODY_TYPE"PLUMBING"
CDS_LIB"mstr_standard";
"B \NAC \NWC"7;
"S \NAC"
BN"5"106;
%"TAP"
"6","(-2875,1250)","2","mstr_standard","I97";
;
HDL_TAP"TRUE"
BODY_TYPE"PLUMBING"
CDS_LIB"mstr_standard";
"B \NAC \NWC"7;
"S \NAC"
BN"6"107;
%"TAP"
"6","(-2875,1300)","2","mstr_standard","I98";
;
HDL_TAP"TRUE"
BODY_TYPE"PLUMBING"
CDS_LIB"mstr_standard";
"B \NAC \NWC"7;
"S \NAC"
BN"7"108;
%"TAP"
"6","(-2875,1400)","2","mstr_standard","I99";
;
HDL_TAP"TRUE"
BODY_TYPE"PLUMBING"
CDS_LIB"mstr_standard";
"B \NAC \NWC"8;
"S \NAC"
BN"0"94;
END.
